(kicad_pcb
	(version 20260206)
	(generator "pcbnew")
	(generator_version "10.0")
	(general
		(thickness 1.6)
		(legacy_teardrops no)
	)
	(paper "A4")
	(title_block
		(title "panther-plus-userver — 13130-1b_20150205.brd")
		(comment 1 "Honey Badger (Wiwynn) / footprints 42-49 of 1509")
	)
	(layers
		(0 "F.Cu" signal "TOP")
		(4 "In1.Cu" signal "L2")
		(6 "In2.Cu" signal "L3")
		(8 "In3.Cu" signal "L4")
		(10 "In4.Cu" signal "L5")
		(12 "In5.Cu" signal "L6")
		(14 "In6.Cu" signal "L7")
		(16 "In7.Cu" signal "L8")
		(18 "In8.Cu" signal "L9")
		(20 "In9.Cu" signal "L10")
		(22 "In10.Cu" signal "L11")
		(2 "B.Cu" signal "BOTTOM")
		(9 "F.Adhes" user "F.Adhesive")
		(11 "B.Adhes" user "B.Adhesive")
		(13 "F.Paste" user "Package Geometry/Pastemask Top")
		(15 "B.Paste" user "Package Geometry/Pastemask Bottom")
		(5 "F.SilkS" user "Ref Des/Silkscreen Top")
		(7 "B.SilkS" user "Ref Des/Silkscreen Bottom")
		(1 "F.Mask" user "Board Geometry/Soldermask Top")
		(3 "B.Mask" user "Board Geometry/Soldermask Bottom")
		(17 "Dwgs.User" user "User.Drawings")
		(19 "Cmts.User" user "User.Comments")
		(21 "Eco1.User" user "User.Eco1")
		(23 "Eco2.User" user "User.Eco2")
		(25 "Edge.Cuts" user "Board Geometry/Outline")
		(27 "Margin" user)
		(31 "F.CrtYd" user "Package Geometry/Place Bound Top")
		(29 "B.CrtYd" user "Package Geometry/Place Bound Bottom")
		(35 "F.Fab" user "Ref Des/Assembly Top")
		(33 "B.Fab" user "Ref Des/Assembly Bottom")
	)
	(footprint ""
		(layer "F.Cu")
		(at 183.261 -22.86 90)
		(property "Reference" "PR60"
			(at 0 0 90)
			(layer "F.SilkS")
			(hide yes)
			(effects
				(font
					(size 1.27 1.27)
				)
			)
		)
		(property "Value" "10R3F-GP"
			(at -0.0254 -2.5146 90)
			(unlocked yes)
			(layer "F.Fab")
			(hide yes)
			(effects
				(font
					(size 1.016 1.016)
					(thickness 0.1524)
				)
			)
		)
		(property "Device Type" "R603H22"
			(at -0.0254 -4.0386 90)
			(unlocked yes)
			(layer "F.Fab")
			(hide yes)
			(effects
				(font
					(size 1.016 1.016)
					(thickness 0.1524)
				)
			)
		)
		(duplicate_pad_numbers_are_jumpers no)
		(fp_line
			(start 0.4318 0)
			(end 0.2032 0)
			(stroke
				(width 0.2032)
				(type default)
			)
			(layer "F.SilkS")
		)
		(fp_line
			(start -0.2032 0)
			(end -0.4191 0)
			(stroke
				(width 0.2032)
				(type default)
			)
			(layer "F.SilkS")
		)
		(fp_rect
			(start -0.635 1.1811)
			(end 0.635 -1.1811)
			(stroke
				(width 0)
				(type default)
			)
			(fill no)
			(layer "F.CrtYd")
		)
		(fp_rect
			(start -0.635 1.1811)
			(end 0.635 -1.1811)
			(stroke
				(width 0)
				(type default)
			)
			(fill no)
			(layer "F.Fab")
		)
		(pad "1" smd custom
			(at 0 -0.6604 90)
			(size 0.19685 0.19685)
			(layers "F.Cu" "F.Mask" "F.Paste")
			(net "P3V3_STBY")
			(options
				(clearance outline)
				(anchor circle)
			)
			(primitives
				(gr_poly
					(pts
						(arc
							(start 0.508 -0.2921)
							(mid 0.478242 -0.363942)
							(end 0.4064 -0.3937)
						)
						(arc
							(start -0.4064 -0.3937)
							(mid -0.478242 -0.363942)
							(end -0.508 -0.2921)
						)
						(arc
							(start -0.508 0.2921)
							(mid -0.478242 0.363942)
							(end -0.4064 0.3937)
						)
						(arc
							(start 0.4064 0.3937)
							(mid 0.478242 0.363942)
							(end 0.508 0.2921)
						)
					)
					(width 0)
					(fill yes)
				)
			)
		)
		(pad "2" smd custom
			(at 0 0.6604 90)
			(size 0.19685 0.19685)
			(layers "F.Cu" "F.Mask" "F.Paste")
			(net "PV_VTT_DDR_B_VIN")
			(options
				(clearance outline)
				(anchor circle)
			)
			(primitives
				(gr_poly
					(pts
						(arc
							(start 0.508 -0.2921)
							(mid 0.478242 -0.363942)
							(end 0.4064 -0.3937)
						)
						(arc
							(start -0.4064 -0.3937)
							(mid -0.478242 -0.363942)
							(end -0.508 -0.2921)
						)
						(arc
							(start -0.508 0.2921)
							(mid -0.478242 0.363942)
							(end -0.4064 0.3937)
						)
						(arc
							(start 0.4064 0.3937)
							(mid 0.478242 0.363942)
							(end 0.508 0.2921)
						)
					)
					(width 0)
					(fill yes)
				)
			)
		)
	)
	(footprint ""
		(layer "F.Cu")
		(at 22.352 -66.421 90)
		(property "Reference" "PC10"
			(at 0 0 90)
			(layer "F.SilkS")
			(hide yes)
			(effects
				(font
					(size 1.27 1.27)
				)
			)
		)
		(property "Value" "SC220P50V2KX-3GP"
			(at 1.8923 -1.2065 90)
			(unlocked yes)
			(layer "F.Fab")
			(hide yes)
			(effects
				(font
					(size 1.016 1.016)
					(thickness 0.1524)
				)
			)
		)
		(property "Device Type" "C402H22"
			(at 1.8923 -2.7305 90)
			(unlocked yes)
			(layer "F.Fab")
			(hide yes)
			(effects
				(font
					(size 1.016 1.016)
					(thickness 0.1524)
				)
			)
		)
		(duplicate_pad_numbers_are_jumpers no)
		(fp_rect
			(start -0.381 0.7366)
			(end 0.381 -0.7366)
			(stroke
				(width 0)
				(type default)
			)
			(fill no)
			(layer "F.CrtYd")
		)
		(fp_rect
			(start -0.381 0.7366)
			(end 0.381 -0.7366)
			(stroke
				(width 0)
				(type default)
			)
			(fill no)
			(layer "F.Fab")
		)
		(pad "1" smd custom
			(at 0 -0.4572 90)
			(size 0.1143 0.1143)
			(layers "F.Cu" "F.Mask" "F.Paste")
			(net "VR_PVNN_ISUMN")
			(options
				(clearance outline)
				(anchor circle)
			)
			(primitives
				(gr_poly
					(pts
						(arc
							(start -0.254 -0.1778)
							(mid -0.239121 -0.213721)
							(end -0.2032 -0.2286)
						)
						(arc
							(start 0.2032 -0.2286)
							(mid 0.239121 -0.213721)
							(end 0.254 -0.1778)
						)
						(arc
							(start 0.254 0.1778)
							(mid 0.239121 0.213721)
							(end 0.2032 0.2286)
						)
						(arc
							(start -0.2032 0.2286)
							(mid -0.239121 0.213721)
							(end -0.254 0.1778)
						)
					)
					(width 0)
					(fill yes)
				)
			)
		)
		(pad "2" smd custom
			(at 0 0.4572 90)
			(size 0.1143 0.1143)
			(layers "F.Cu" "F.Mask" "F.Paste")
			(net "VR_PVNN_ISUMN_RC")
			(options
				(clearance outline)
				(anchor circle)
			)
			(primitives
				(gr_poly
					(pts
						(arc
							(start -0.254 -0.1778)
							(mid -0.239121 -0.213721)
							(end -0.2032 -0.2286)
						)
						(arc
							(start 0.2032 -0.2286)
							(mid 0.239121 -0.213721)
							(end 0.254 -0.1778)
						)
						(arc
							(start 0.254 0.1778)
							(mid 0.239121 0.213721)
							(end 0.2032 0.2286)
						)
						(arc
							(start -0.2032 0.2286)
							(mid -0.239121 0.213721)
							(end -0.254 0.1778)
						)
					)
					(width 0)
					(fill yes)
				)
			)
		)
	)
	(footprint ""
		(layer "F.Cu")
		(at 73.66 -36.576 90)
		(property "Reference" "R103"
			(at 0 0 90)
			(layer "F.SilkS")
			(hide yes)
			(effects
				(font
					(size 1.27 1.27)
				)
			)
		)
		(property "Value" "1KR2F-3-GP"
			(at 0.064008 -3.993896 90)
			(unlocked yes)
			(layer "F.Fab")
			(hide yes)
			(effects
				(font
					(size 1.016 1.016)
					(thickness 0.1524)
				)
			)
		)
		(property "Device Type" "R402H16"
			(at 0.064008 -5.517896 90)
			(unlocked yes)
			(layer "F.Fab")
			(hide yes)
			(effects
				(font
					(size 1.016 1.016)
					(thickness 0.1524)
				)
			)
		)
		(duplicate_pad_numbers_are_jumpers no)
		(fp_rect
			(start -0.381 0.8382)
			(end 0.381 -0.8382)
			(stroke
				(width 0)
				(type default)
			)
			(fill no)
			(layer "F.CrtYd")
		)
		(fp_rect
			(start -0.381 0.8382)
			(end 0.381 -0.8382)
			(stroke
				(width 0)
				(type default)
			)
			(fill no)
			(layer "F.Fab")
		)
		(pad "1" smd custom
			(at 0 -0.4318 90)
			(size 0.127 0.127)
			(layers "F.Cu" "F.Mask" "F.Paste")
			(net "P3V3_CPU")
			(options
				(clearance outline)
				(anchor circle)
			)
			(primitives
				(gr_poly
					(pts
						(arc
							(start -0.2032 -0.2794)
							(mid -0.239121 -0.264521)
							(end -0.254 -0.2286)
						)
						(arc
							(start -0.254 0.2286)
							(mid -0.239121 0.264521)
							(end -0.2032 0.2794)
						)
						(arc
							(start 0.2032 0.2794)
							(mid 0.239121 0.264521)
							(end 0.254 0.2286)
						)
						(arc
							(start 0.254 -0.2286)
							(mid 0.239121 -0.264521)
							(end 0.2032 -0.2794)
						)
					)
					(width 0)
					(fill yes)
				)
			)
		)
		(pad "2" smd custom
			(at 0 0.4318 90)
			(size 0.127 0.127)
			(layers "F.Cu" "F.Mask" "F.Paste")
			(net "PMU_WAKE#")
			(options
				(clearance outline)
				(anchor circle)
			)
			(primitives
				(gr_poly
					(pts
						(arc
							(start -0.2032 -0.2794)
							(mid -0.239121 -0.264521)
							(end -0.254 -0.2286)
						)
						(arc
							(start -0.254 0.2286)
							(mid -0.239121 0.264521)
							(end -0.2032 0.2794)
						)
						(arc
							(start 0.2032 0.2794)
							(mid 0.239121 0.264521)
							(end 0.254 0.2286)
						)
						(arc
							(start 0.254 -0.2286)
							(mid 0.239121 -0.264521)
							(end 0.2032 -0.2794)
						)
					)
					(width 0)
					(fill yes)
				)
			)
		)
	)
	(footprint ""
		(layer "F.Cu")
		(at 88.011 -15.113)
		(property "Reference" "PC196"
			(at 0 0 0)
			(layer "F.SilkS")
			(hide yes)
			(effects
				(font
					(size 1.27 1.27)
				)
			)
		)
		(property "Value" "SC10U6D3V5KX-4GP"
			(at -0.0762 -6.1214 0)
			(unlocked yes)
			(layer "F.Fab")
			(hide yes)
			(effects
				(font
					(size 1.016 1.016)
					(thickness 0.1524)
				)
			)
		)
		(property "Device Type" "C805H58"
			(at -0.0762 -8.1534 0)
			(unlocked yes)
			(layer "F.Fab")
			(hide yes)
			(effects
				(font
					(size 1.016 1.016)
					(thickness 0.1524)
				)
			)
		)
		(duplicate_pad_numbers_are_jumpers no)
		(fp_line
			(start 0.6096 0)
			(end -0.6096 0)
			(stroke
				(width 0.3048)
				(type default)
			)
			(layer "F.SilkS")
		)
		(fp_poly
			(pts
				(xy -0.9017 1.4351) (xy 0.9017 1.4351) (xy 0.9017 -1.4351) (xy -0.9017 -1.4351)
			)
			(stroke
				(width 0)
				(type default)
			)
			(fill no)
			(layer "F.CrtYd")
		)
		(fp_poly
			(pts
				(xy 0.9017 1.4351) (xy 0.9017 -1.4351) (xy -0.9017 -1.4351) (xy -0.9017 1.4351)
			)
			(stroke
				(width 0)
				(type default)
			)
			(fill no)
			(layer "F.Fab")
		)
		(pad "1" smd rect
			(at 0 -0.8382)
			(size 1.5494 0.9398)
			(layers "F.Cu" "F.Mask" "F.Paste")
			(net "TPS74801_1V35_OUT")
		)
		(pad "2" smd rect
			(at 0 0.8382)
			(size 1.5494 0.9398)
			(layers "F.Cu" "F.Mask" "F.Paste")
			(net "GND")
		)
	)
	(footprint ""
		(layer "F.Cu")
		(at 167.894 -26.67 -90)
		(property "Reference" "PC96"
			(at 0 0 270)
			(layer "F.SilkS")
			(hide yes)
			(effects
				(font
					(size 1.27 1.27)
				)
			)
		)
		(property "Value" "SC22U6D3V5MX-2GP"
			(at -0.0762 -6.1214 270)
			(unlocked yes)
			(layer "F.Fab")
			(hide yes)
			(effects
				(font
					(size 1.016 1.016)
					(thickness 0.1524)
				)
			)
		)
		(property "Device Type" "C805H58"
			(at -0.0762 -8.1534 270)
			(unlocked yes)
			(layer "F.Fab")
			(hide yes)
			(effects
				(font
					(size 1.016 1.016)
					(thickness 0.1524)
				)
			)
		)
		(duplicate_pad_numbers_are_jumpers no)
		(fp_line
			(start 0.6096 0)
			(end -0.6096 0)
			(stroke
				(width 0.3048)
				(type default)
			)
			(layer "F.SilkS")
		)
		(fp_poly
			(pts
				(xy -0.9017 1.4351) (xy 0.9017 1.4351) (xy 0.9017 -1.4351) (xy -0.9017 -1.4351)
			)
			(stroke
				(width 0)
				(type default)
			)
			(fill no)
			(layer "F.CrtYd")
		)
		(fp_poly
			(pts
				(xy 0.9017 1.4351) (xy 0.9017 -1.4351) (xy -0.9017 -1.4351) (xy -0.9017 1.4351)
			)
			(stroke
				(width 0)
				(type default)
			)
			(fill no)
			(layer "F.Fab")
		)
		(pad "1" smd rect
			(at 0 -0.8382 270)
			(size 1.5494 0.9398)
			(layers "F.Cu" "F.Mask" "F.Paste")
			(net "P1V2_STBY_LDO_OUT2")
		)
		(pad "2" smd rect
			(at 0 0.8382 270)
			(size 1.5494 0.9398)
			(layers "F.Cu" "F.Mask" "F.Paste")
			(net "GND")
		)
	)
	(footprint ""
		(layer "F.Cu")
		(at 109.601 -57.912 90)
		(property "Reference" "R23"
			(at 0 0 90)
			(layer "F.SilkS")
			(hide yes)
			(effects
				(font
					(size 1.27 1.27)
				)
			)
		)
		(property "Value" "100R2F-L1-GP-U"
			(at 0.064008 -3.993896 90)
			(unlocked yes)
			(layer "F.Fab")
			(hide yes)
			(effects
				(font
					(size 1.016 1.016)
					(thickness 0.1524)
				)
			)
		)
		(property "Device Type" "R402H14"
			(at 0.064008 -5.517896 90)
			(unlocked yes)
			(layer "F.Fab")
			(hide yes)
			(effects
				(font
					(size 1.016 1.016)
					(thickness 0.1524)
				)
			)
		)
		(duplicate_pad_numbers_are_jumpers no)
		(fp_rect
			(start -0.381 0.8382)
			(end 0.381 -0.8382)
			(stroke
				(width 0)
				(type default)
			)
			(fill no)
			(layer "F.CrtYd")
		)
		(fp_rect
			(start -0.381 0.8382)
			(end 0.381 -0.8382)
			(stroke
				(width 0)
				(type default)
			)
			(fill no)
			(layer "F.Fab")
		)
		(pad "1" smd custom
			(at 0 -0.4318 90)
			(size 0.127 0.127)
			(layers "F.Cu" "F.Mask" "F.Paste")
			(net "M_A_MON1_P")
			(options
				(clearance outline)
				(anchor circle)
			)
			(primitives
				(gr_poly
					(pts
						(arc
							(start -0.2032 -0.2794)
							(mid -0.239121 -0.264521)
							(end -0.254 -0.2286)
						)
						(arc
							(start -0.254 0.2286)
							(mid -0.239121 0.264521)
							(end -0.2032 0.2794)
						)
						(arc
							(start 0.2032 0.2794)
							(mid 0.239121 0.264521)
							(end 0.254 0.2286)
						)
						(arc
							(start 0.254 -0.2286)
							(mid 0.239121 -0.264521)
							(end 0.2032 -0.2794)
						)
					)
					(width 0)
					(fill yes)
				)
			)
		)
		(pad "2" smd custom
			(at 0 0.4318 90)
			(size 0.127 0.127)
			(layers "F.Cu" "F.Mask" "F.Paste")
			(net "M_A_MON1_N")
			(options
				(clearance outline)
				(anchor circle)
			)
			(primitives
				(gr_poly
					(pts
						(arc
							(start -0.2032 -0.2794)
							(mid -0.239121 -0.264521)
							(end -0.254 -0.2286)
						)
						(arc
							(start -0.254 0.2286)
							(mid -0.239121 0.264521)
							(end -0.2032 0.2794)
						)
						(arc
							(start 0.2032 0.2794)
							(mid 0.239121 0.264521)
							(end 0.254 0.2286)
						)
						(arc
							(start 0.254 -0.2286)
							(mid 0.239121 -0.264521)
							(end 0.2032 -0.2794)
						)
					)
					(width 0)
					(fill yes)
				)
			)
		)
	)
	(footprint ""
		(layer "F.Cu")
		(at 112.1664 -64.2874 180)
		(property "Reference" "R17"
			(at 0 0 180)
			(layer "F.SilkS")
			(hide yes)
			(effects
				(font
					(size 1.27 1.27)
				)
			)
		)
		(property "Value" "20KR2F-L-GP"
			(at 0.064008 -3.993896 180)
			(unlocked yes)
			(layer "F.Fab")
			(hide yes)
			(effects
				(font
					(size 1.016 1.016)
					(thickness 0.1524)
				)
			)
		)
		(property "Device Type" "R402H16"
			(at 0.064008 -5.517896 180)
			(unlocked yes)
			(layer "F.Fab")
			(hide yes)
			(effects
				(font
					(size 1.016 1.016)
					(thickness 0.1524)
				)
			)
		)
		(duplicate_pad_numbers_are_jumpers no)
		(fp_rect
			(start -0.381 0.8382)
			(end 0.381 -0.8382)
			(stroke
				(width 0)
				(type default)
			)
			(fill no)
			(layer "F.CrtYd")
		)
		(fp_rect
			(start -0.381 0.8382)
			(end 0.381 -0.8382)
			(stroke
				(width 0)
				(type default)
			)
			(fill no)
			(layer "F.Fab")
		)
		(pad "1" smd custom
			(at 0 -0.4318 180)
			(size 0.127 0.127)
			(layers "F.Cu" "F.Mask" "F.Paste")
			(net "CLK_GEN_PG")
			(options
				(clearance outline)
				(anchor circle)
			)
			(primitives
				(gr_poly
					(pts
						(arc
							(start -0.2032 -0.2794)
							(mid -0.239121 -0.264521)
							(end -0.254 -0.2286)
						)
						(arc
							(start -0.254 0.2286)
							(mid -0.239121 0.264521)
							(end -0.2032 0.2794)
						)
						(arc
							(start 0.2032 0.2794)
							(mid 0.239121 0.264521)
							(end 0.254 0.2286)
						)
						(arc
							(start 0.254 -0.2286)
							(mid 0.239121 -0.264521)
							(end 0.2032 -0.2794)
						)
					)
					(width 0)
					(fill yes)
				)
			)
		)
		(pad "2" smd custom
			(at 0 0.4318 180)
			(size 0.127 0.127)
			(layers "F.Cu" "F.Mask" "F.Paste")
			(net "CLK_GEN_INA_PG")
			(options
				(clearance outline)
				(anchor circle)
			)
			(primitives
				(gr_poly
					(pts
						(arc
							(start -0.2032 -0.2794)
							(mid -0.239121 -0.264521)
							(end -0.254 -0.2286)
						)
						(arc
							(start -0.254 0.2286)
							(mid -0.239121 0.264521)
							(end -0.2032 0.2794)
						)
						(arc
							(start 0.2032 0.2794)
							(mid 0.239121 0.264521)
							(end 0.254 0.2286)
						)
						(arc
							(start 0.254 -0.2286)
							(mid 0.239121 -0.264521)
							(end 0.2032 -0.2794)
						)
					)
					(width 0)
					(fill yes)
				)
			)
		)
	)
	(footprint ""
		(layer "F.Cu")
		(at 113.792 -64.262)
		(property "Reference" "C5"
			(at 0 0 0)
			(layer "F.SilkS")
			(hide yes)
			(effects
				(font
					(size 1.27 1.27)
				)
			)
		)
		(property "Value" "SC2D2U10V2KX-GP"
			(at 1.8923 -1.2065 0)
			(unlocked yes)
			(layer "F.Fab")
			(hide yes)
			(effects
				(font
					(size 1.016 1.016)
					(thickness 0.1524)
				)
			)
		)
		(property "Device Type" "C402H22"
			(at 1.8923 -2.7305 0)
			(unlocked yes)
			(layer "F.Fab")
			(hide yes)
			(effects
				(font
					(size 1.016 1.016)
					(thickness 0.1524)
				)
			)
		)
		(duplicate_pad_numbers_are_jumpers no)
		(fp_rect
			(start -0.381 0.7366)
			(end 0.381 -0.7366)
			(stroke
				(width 0)
				(type default)
			)
			(fill no)
			(layer "F.CrtYd")
		)
		(fp_rect
			(start -0.381 0.7366)
			(end 0.381 -0.7366)
			(stroke
				(width 0)
				(type default)
			)
			(fill no)
			(layer "F.Fab")
		)
		(pad "1" smd custom
			(at 0 -0.4572)
			(size 0.1143 0.1143)
			(layers "F.Cu" "F.Mask" "F.Paste")
			(net "CLK_GEN_INA_PG")
			(options
				(clearance outline)
				(anchor circle)
			)
			(primitives
				(gr_poly
					(pts
						(arc
							(start -0.254 -0.1778)
							(mid -0.239121 -0.213721)
							(end -0.2032 -0.2286)
						)
						(arc
							(start 0.2032 -0.2286)
							(mid 0.239121 -0.213721)
							(end 0.254 -0.1778)
						)
						(arc
							(start 0.254 0.1778)
							(mid 0.239121 0.213721)
							(end 0.2032 0.2286)
						)
						(arc
							(start -0.2032 0.2286)
							(mid -0.239121 0.213721)
							(end -0.254 0.1778)
						)
					)
					(width 0)
					(fill yes)
				)
			)
		)
		(pad "2" smd custom
			(at 0 0.4572)
			(size 0.1143 0.1143)
			(layers "F.Cu" "F.Mask" "F.Paste")
			(net "GND")
			(options
				(clearance outline)
				(anchor circle)
			)
			(primitives
				(gr_poly
					(pts
						(arc
							(start -0.254 -0.1778)
							(mid -0.239121 -0.213721)
							(end -0.2032 -0.2286)
						)
						(arc
							(start 0.2032 -0.2286)
							(mid 0.239121 -0.213721)
							(end 0.254 -0.1778)
						)
						(arc
							(start 0.254 0.1778)
							(mid 0.239121 0.213721)
							(end 0.2032 0.2286)
						)
						(arc
							(start -0.2032 0.2286)
							(mid -0.239121 0.213721)
							(end -0.254 0.1778)
						)
					)
					(width 0)
					(fill yes)
				)
			)
		)
	)
)
